(kicad_pcb
	(version 20241229)
	(generator "pcbnew")
	(generator_version "9.0")
	(general
		(thickness 1.6)
		(legacy_teardrops no)
	)
	(paper "A4")
	(title_block
		(title "OCuLink to PCIe adapter")
		(date "2025-06-18")
		(rev "1.0.0")
		(company "Antmicro Ltd")
		(comment 1 "www.antmicro.com")
		(comment 9 "footprints 106-110 of 159")
	)
	(layers
		(0 "F.Cu" signal)
		(4 "In1.Cu" signal)
		(6 "In2.Cu" signal)
		(2 "B.Cu" signal)
		(9 "F.Adhes" user "F.Adhesive")
		(11 "B.Adhes" user "B.Adhesive")
		(13 "F.Paste" user)
		(15 "B.Paste" user)
		(5 "F.SilkS" user "F.Silkscreen")
		(7 "B.SilkS" user "B.Silkscreen")
		(1 "F.Mask" user)
		(3 "B.Mask" user)
		(17 "Dwgs.User" user "User.Drawings")
		(19 "Cmts.User" user "User.Comments")
		(21 "Eco1.User" user "User.Eco1")
		(23 "Eco2.User" user "User.Eco2")
		(25 "Edge.Cuts" user)
		(27 "Margin" user)
		(31 "F.CrtYd" user "F.Courtyard")
		(29 "B.CrtYd" user "B.Courtyard")
		(35 "F.Fab" user)
		(33 "B.Fab" user)
	)
	(footprint "antmicro-footprints:C_0402_1005Metric"
		(layer "F.Cu")
		(at 148.152 97)
		(descr "Capacitor SMD 0402")
		(tags "capacitor SMD 0402")
		(property "Reference" "C23"
			(at 1.248 0.4 180)
			(layer "F.SilkS")
			(effects
				(font
					(size 0.7 0.7)
					(thickness 0.15)
				)
				(justify left bottom)
			)
		)
		(property "Value" "C_33n_0402"
			(at -1.022927 2.155213 0)
			(layer "F.Fab")
			(effects
				(font
					(size 0.7 0.7)
					(thickness 0.15)
				)
				(justify left bottom)
			)
		)
		(property "Datasheet" "https://www.murata.com/products/productdetail?partno=GCM155R71E333KA55%23"
			(at 0 0 0)
			(layer "F.Fab")
			(hide yes)
			(effects
				(font
					(size 1.27 1.27)
					(thickness 0.15)
				)
			)
		)
		(property "Description" "SMD Multilayer Ceramic Capacitor, 33000 pF, 25 V, 0402 [1005 Metric], ± 10%, X7R, MC"
			(at 0 0 0)
			(layer "F.Fab")
			(hide yes)
			(effects
				(font
					(size 1.27 1.27)
					(thickness 0.15)
				)
			)
		)
		(property "Manufacturer" "Murata"
			(at 0 0 0)
			(unlocked yes)
			(layer "F.Fab")
			(hide yes)
			(effects
				(font
					(size 1 1)
					(thickness 0.15)
				)
			)
		)
		(property "MPN" "GCM155R71E333KA55D"
			(at 0 0 0)
			(unlocked yes)
			(layer "F.Fab")
			(hide yes)
			(effects
				(font
					(size 1 1)
					(thickness 0.15)
				)
			)
		)
		(property "Val" "33n"
			(at 0 0 0)
			(unlocked yes)
			(layer "F.Fab")
			(hide yes)
			(effects
				(font
					(size 1 1)
					(thickness 0.15)
				)
			)
		)
		(property "License" "Apache-2.0"
			(at 0 0 0)
			(unlocked yes)
			(layer "F.Fab")
			(hide yes)
			(effects
				(font
					(size 1 1)
					(thickness 0.15)
				)
			)
		)
		(property "Author" "Antmicro"
			(at 0 0 0)
			(unlocked yes)
			(layer "F.Fab")
			(hide yes)
			(effects
				(font
					(size 1 1)
					(thickness 0.15)
				)
			)
		)
		(property "Voltage" ""
			(at 0 0 0)
			(unlocked yes)
			(layer "F.Fab")
			(hide yes)
			(effects
				(font
					(size 1 1)
					(thickness 0.15)
				)
			)
		)
		(property "Dielectric" ""
			(at 0 0 0)
			(unlocked yes)
			(layer "F.Fab")
			(hide yes)
			(effects
				(font
					(size 1 1)
					(thickness 0.15)
				)
			)
		)
		(sheetname "/USB-PD/")
		(sheetfile "usb-pd.kicad_sch")
		(attr smd)
		(fp_rect
			(start -0.925 -0.47)
			(end 0.925 0.47)
			(stroke
				(width 0.05)
				(type default)
			)
			(fill no)
			(layer "F.CrtYd")
		)
		(fp_line
			(start -0.494 -0.25)
			(end 0.504 -0.25)
			(stroke
				(width 0.15)
				(type solid)
			)
			(layer "F.Fab")
		)
		(fp_line
			(start -0.494 0.248)
			(end -0.494 -0.25)
			(stroke
				(width 0.15)
				(type solid)
			)
			(layer "F.Fab")
		)
		(fp_line
			(start 0.504 -0.25)
			(end 0.504 0.248)
			(stroke
				(width 0.15)
				(type solid)
			)
			(layer "F.Fab")
		)
		(fp_line
			(start 0.504 0.248)
			(end -0.494 0.248)
			(stroke
				(width 0.15)
				(type solid)
			)
			(layer "F.Fab")
		)
		(fp_text user "License: Apache-2.0"
			(at -0.939 5.799 0)
			(layer "F.Fab")
			(effects
				(font
					(size 0.7 0.7)
					(thickness 0.15)
				)
				(justify left bottom)
			)
		)
		(fp_text user "${REFERENCE}"
			(at 0 0 0)
			(layer "F.Fab")
			(effects
				(font
					(size 0.7 0.7)
					(thickness 0.15)
				)
				(justify left bottom)
			)
		)
		(fp_text user "Author: Antmicro"
			(at -0.939 3.399 0)
			(layer "F.Fab")
			(effects
				(font
					(size 0.7 0.7)
					(thickness 0.15)
				)
				(justify left bottom)
			)
		)
		(pad "1" smd roundrect
			(at -0.48 0)
			(size 0.59 0.64)
			(layers "F.Cu" "F.Mask" "F.Paste")
			(roundrect_rratio 0.25)
			(net 125 "/USB-PD/12V_SS")
			(pintype "passive")
		)
		(pad "2" smd roundrect
			(at 0.48 0)
			(size 0.59 0.64)
			(layers "F.Cu" "F.Mask" "F.Paste")
			(roundrect_rratio 0.25)
			(net 66 "GND")
			(pintype "passive")
		)
	)
	(footprint "antmicro-footprints:Vishay_PowerPAK_1212-8_Single"
		(layer "F.Cu")
		(at 141 141)
		(descr "PowerPAK 1212-8 Single")
		(tags "Vishay PowerPAK 1212-8 Single")
		(property "Reference" "Q7"
			(at -3.6 -1 180)
			(layer "F.SilkS")
			(effects
				(font
					(size 0.7 0.7)
					(thickness 0.15)
				)
				(justify left bottom)
			)
		)
		(property "Value" "SQS401EN-T1_BE3"
			(at 0 2.7 0)
			(layer "F.Fab")
			(effects
				(font
					(size 0.7 0.7)
					(thickness 0.15)
				)
				(justify left bottom)
			)
		)
		(property "Datasheet" "https://www.vishay.com/docs/65529/sqs401en.pdf"
			(at 0 0 0)
			(layer "F.Fab")
			(hide yes)
			(effects
				(font
					(size 1.27 1.27)
					(thickness 0.15)
				)
			)
		)
		(property "Description" "MOSFET, P Channel, 40 V, 16A, 0.047 ohm, PowerPAK 1212-8, Surface Mount"
			(at 0 0 0)
			(layer "F.Fab")
			(hide yes)
			(effects
				(font
					(size 1.27 1.27)
					(thickness 0.15)
				)
			)
		)
		(property "MPN" "SQS401EN-T1_BE3"
			(at 0 0 0)
			(unlocked yes)
			(layer "F.Fab")
			(hide yes)
			(effects
				(font
					(size 1 1)
					(thickness 0.15)
				)
			)
		)
		(property "Manufacturer" "Vishay"
			(at 0 0 0)
			(unlocked yes)
			(layer "F.Fab")
			(hide yes)
			(effects
				(font
					(size 1 1)
					(thickness 0.15)
				)
			)
		)
		(property "Author" "Antmicro"
			(at 0 0 0)
			(unlocked yes)
			(layer "F.Fab")
			(hide yes)
			(effects
				(font
					(size 1 1)
					(thickness 0.15)
				)
			)
		)
		(property "License" "Apache-2.0"
			(at 0 0 0)
			(unlocked yes)
			(layer "F.Fab")
			(hide yes)
			(effects
				(font
					(size 1 1)
					(thickness 0.15)
				)
			)
		)
		(sheetname "/Power/Ideal-diode-2/")
		(sheetfile "ideal-diode.kicad_sch")
		(attr smd)
		(fp_line
			(start -1.651 -1.651)
			(end -1.651 -1.317)
			(stroke
				(width 0.15)
				(type solid)
			)
			(layer "F.SilkS")
		)
		(fp_line
			(start -1.651 -1.651)
			(end 1.648 -1.651)
			(stroke
				(width 0.15)
				(type solid)
			)
			(layer "F.SilkS")
		)
		(fp_line
			(start -1.635 1.3)
			(end -1.635 1.634)
			(stroke
				(width 0.15)
				(type solid)
			)
			(layer "F.SilkS")
		)
		(fp_line
			(start -1.635 1.634)
			(end 1.634 1.634)
			(stroke
				(width 0.15)
				(type solid)
			)
			(layer "F.SilkS")
		)
		(fp_line
			(start 1.634 1.3)
			(end 1.634 1.634)
			(stroke
				(width 0.15)
				(type solid)
			)
			(layer "F.SilkS")
		)
		(fp_line
			(start 1.648 -1.651)
			(end 1.648 -1.317)
			(stroke
				(width 0.15)
				(type solid)
			)
			(layer "F.SilkS")
		)
		(fp_circle
			(center -1.9 -1.4)
			(end -1.85 -1.4)
			(stroke
				(width 0.15)
				(type solid)
			)
			(fill yes)
			(layer "F.SilkS")
		)
		(fp_rect
			(start -2 -1.8)
			(end 2 1.798)
			(stroke
				(width 0.05)
				(type solid)
			)
			(fill no)
			(layer "F.CrtYd")
		)
		(fp_line
			(start -1.6425 -1.4175)
			(end -1.4175 -1.6425)
			(stroke
				(width 0.15)
				(type solid)
			)
			(layer "F.Fab")
		)
		(fp_rect
			(start -1.651 -1.651)
			(end 1.648 1.648)
			(stroke
				(width 0.15)
				(type solid)
			)
			(fill no)
			(layer "F.Fab")
		)
		(fp_text user "Author: Antmicro"
			(at -8 5.9 0)
			(layer "F.Fab")
			(effects
				(font
					(size 0.7 0.7)
					(thickness 0.15)
				)
				(justify left bottom)
			)
		)
		(fp_text user "License: Apache-2.0"
			(at -8 7.1 0)
			(layer "F.Fab")
			(effects
				(font
					(size 0.7 0.7)
					(thickness 0.15)
				)
				(justify left bottom)
			)
		)
		(fp_text user "${REFERENCE}"
			(at 0 -0.001 0)
			(layer "F.Fab")
			(effects
				(font
					(size 0.7 0.7)
					(thickness 0.15)
				)
				(justify left bottom)
			)
		)
		(pad "1" smd rect
			(at -1.436 -0.99)
			(size 0.99 0.405)
			(layers "F.Cu" "F.Mask" "F.Paste")
			(net 87 "+12V")
			(pinfunction "S")
			(pintype "passive")
		)
		(pad "2" smd rect
			(at -1.436 -0.332)
			(size 0.99 0.405)
			(layers "F.Cu" "F.Mask" "F.Paste")
			(net 87 "+12V")
			(pinfunction "S")
			(pintype "passive")
		)
		(pad "3" smd rect
			(at -1.436 0.33)
			(size 0.99 0.405)
			(layers "F.Cu" "F.Mask" "F.Paste")
			(net 87 "+12V")
			(pinfunction "S")
			(pintype "passive")
		)
		(pad "4" smd rect
			(at -1.436 0.988)
			(size 0.99 0.405)
			(layers "F.Cu" "F.Mask" "F.Paste")
			(net 175 "Net-(Q7-G)")
			(pinfunction "G")
			(pintype "input")
		)
		(pad "5" smd custom
			(at 0.557 0)
			(size 1.725 2.235)
			(layers "F.Cu" "F.Mask" "F.Paste")
			(net 116 "/Power/Ideal-diode-2/VIN")
			(pinfunction "D")
			(pintype "passive")
			(zone_connect 2)
			(options
				(clearance outline)
				(anchor rect)
			)
			(primitives
				(gr_poly
					(pts
						(xy 0.8625 0.1275) (xy 0.8625 -0.1275) (xy 1.3725 -0.1275) (xy 1.3725 -0.5325) (xy 0.8625 -0.5325)
						(xy 0.8625 -0.7875) (xy 1.3725 -0.7875) (xy 1.3725 -1.195) (xy 0.6125 -1.195) (xy 0.6125 1.195)
						(xy 1.3725 1.195) (xy 1.3725 0.7875) (xy 0.8625 0.7875) (xy 0.8625 0.5325) (xy 1.3725 0.5325)
						(xy 1.3725 0.1275)
					)
					(width 0)
					(fill yes)
				)
			)
		)
	)
	(footprint "antmicro-footprints:R_0402_1005Metric"
		(layer "F.Cu")
		(at 149.737 57.376 90)
		(descr "Resistor SMD 0402")
		(tags "resistor SMD 0402")
		(property "Reference" "R22"
			(at -3.274 0.439001 90)
			(layer "F.SilkS")
			(effects
				(font
					(size 0.7 0.7)
					(thickness 0.15)
				)
				(justify left bottom)
			)
		)
		(property "Value" "R_1k_0402"
			(at -1.011843 1.772046 90)
			(layer "F.Fab")
			(effects
				(font
					(size 0.7 0.7)
					(thickness 0.15)
				)
				(justify left bottom)
			)
		)
		(property "Datasheet" "https://www.bourns.com/docs/product-datasheets/cr.pdf"
			(at 0 0 90)
			(layer "F.Fab")
			(hide yes)
			(effects
				(font
					(size 1.27 1.27)
					(thickness 0.15)
				)
			)
		)
		(property "Description" "SMD Chip Resistor, 1 kohm, ± 1%, 63 mW, 0402 [1005 Metric], Thick Film, General Purpose"
			(at 0 0 90)
			(layer "F.Fab")
			(hide yes)
			(effects
				(font
					(size 1.27 1.27)
					(thickness 0.15)
				)
			)
		)
		(property "MPN" "CR0402-FX-1001GLF"
			(at 0 0 90)
			(unlocked yes)
			(layer "F.Fab")
			(hide yes)
			(effects
				(font
					(size 1 1)
					(thickness 0.15)
				)
			)
		)
		(property "Manufacturer" "Bourns"
			(at 0 0 90)
			(unlocked yes)
			(layer "F.Fab")
			(hide yes)
			(effects
				(font
					(size 1 1)
					(thickness 0.15)
				)
			)
		)
		(property "License" "Apache-2.0"
			(at 0 0 90)
			(unlocked yes)
			(layer "F.Fab")
			(hide yes)
			(effects
				(font
					(size 1 1)
					(thickness 0.15)
				)
			)
		)
		(property "Author" "Antmicro"
			(at 0 0 90)
			(unlocked yes)
			(layer "F.Fab")
			(hide yes)
			(effects
				(font
					(size 1 1)
					(thickness 0.15)
				)
			)
		)
		(property "Val" "1k"
			(at 0 0 90)
			(unlocked yes)
			(layer "F.Fab")
			(hide yes)
			(effects
				(font
					(size 1 1)
					(thickness 0.15)
				)
			)
		)
		(property "Tolerance" "1%"
			(at 0 0 90)
			(unlocked yes)
			(layer "F.Fab")
			(hide yes)
			(effects
				(font
					(size 1 1)
					(thickness 0.15)
				)
			)
		)
		(sheetname "/USB-PD/")
		(sheetfile "usb-pd.kicad_sch")
		(attr smd exclude_from_bom dnp)
		(fp_rect
			(start -0.925 -0.47)
			(end 0.925 0.47)
			(stroke
				(width 0.05)
				(type default)
			)
			(fill no)
			(layer "F.CrtYd")
		)
		(fp_rect
			(start -0.5 -0.25)
			(end 0.5 0.25)
			(stroke
				(width 0.15)
				(type solid)
			)
			(fill no)
			(layer "F.Fab")
		)
		(fp_text user "License: Apache-2.0"
			(at -0.949999 5.169 90)
			(layer "F.Fab")
			(effects
				(font
					(size 0.7 0.7)
					(thickness 0.15)
				)
				(justify left bottom)
			)
		)
		(fp_text user "Author: Antmicro"
			(at -0.95 4.169 90)
			(layer "F.Fab")
			(effects
				(font
					(size 0.7 0.7)
					(thickness 0.15)
				)
				(justify left bottom)
			)
		)
		(fp_text user "${REFERENCE}"
			(at 0 0 90)
			(layer "F.Fab")
			(effects
				(font
					(size 0.7 0.7)
					(thickness 0.15)
				)
				(justify left bottom)
			)
		)
		(pad "1" smd roundrect
			(at -0.48 0 90)
			(size 0.59 0.64)
			(layers "F.Cu" "F.Mask" "F.Paste")
			(roundrect_rratio 0.25)
			(net 66 "GND")
			(pintype "passive")
		)
		(pad "2" smd roundrect
			(at 0.48 0 90)
			(size 0.59 0.64)
			(layers "F.Cu" "F.Mask" "F.Paste")
			(roundrect_rratio 0.25)
			(net 136 "/USB-PD/VBUS_MAX")
			(pintype "passive")
		)
	)
	(footprint "antmicro-footprints:TP_Pad0.75mm_Drill0.2mm"
		(layer "F.Cu")
		(at 117.6 140.6 180)
		(property "Reference" "TP7"
			(at 2.75 -0.6 180)
			(layer "F.SilkS")
			(effects
				(font
					(size 0.7 0.7)
					(thickness 0.15)
				)
				(justify left bottom)
			)
		)
		(property "Value" "TP_Pad0.75mm_Drill0.2mm"
			(at 0 1.2 180)
			(layer "F.Fab")
			(effects
				(font
					(size 0.7 0.7)
					(thickness 0.15)
				)
				(justify left bottom)
			)
		)
		(property "Description" "SMT test point"
			(at 0 0 180)
			(layer "F.Fab")
			(hide yes)
			(effects
				(font
					(size 1.27 1.27)
					(thickness 0.15)
				)
			)
		)
		(property "MPN" ""
			(at 0 0 180)
			(unlocked yes)
			(layer "F.Fab")
			(hide yes)
			(effects
				(font
					(size 1 1)
					(thickness 0.15)
				)
			)
		)
		(property "Manufacturer" ""
			(at 0 0 180)
			(unlocked yes)
			(layer "F.Fab")
			(hide yes)
			(effects
				(font
					(size 1 1)
					(thickness 0.15)
				)
			)
		)
		(property "Author" "Antmicro"
			(at 0 0 180)
			(unlocked yes)
			(layer "F.Fab")
			(hide yes)
			(effects
				(font
					(size 1 1)
					(thickness 0.15)
				)
			)
		)
		(property "License" "Apache-2.0"
			(at 0 0 180)
			(unlocked yes)
			(layer "F.Fab")
			(hide yes)
			(effects
				(font
					(size 1 1)
					(thickness 0.15)
				)
			)
		)
		(sheetname "/Power/")
		(sheetfile "power.kicad_sch")
		(attr exclude_from_pos_files exclude_from_bom)
		(fp_circle
			(center 0 0)
			(end 0.475 0)
			(stroke
				(width 0.05)
				(type default)
			)
			(fill no)
			(layer "F.CrtYd")
		)
		(fp_text user "Author: Antmicro"
			(at -0.4 3.901 180)
			(layer "F.Fab")
			(effects
				(font
					(size 0.7 0.7)
					(thickness 0.15)
				)
				(justify left bottom)
			)
		)
		(fp_text user "${REFERENCE}"
			(at -0.4 2.7 180)
			(layer "F.Fab")
			(effects
				(font
					(size 0.7 0.7)
					(thickness 0.15)
				)
				(justify left bottom)
			)
		)
		(fp_text user "License: Apache-2.0"
			(at -0.4 5.101 180)
			(layer "F.Fab")
			(effects
				(font
					(size 0.7 0.7)
					(thickness 0.15)
				)
				(justify left bottom)
			)
		)
		(pad "1" thru_hole circle
			(at 0 0 180)
			(size 0.75 0.75)
			(drill 0.2)
			(layers "*.Cu" "*.Mask")
			(remove_unused_layers no)
			(net 186 "/Power/3V3_CONV")
			(pinfunction "1")
			(pintype "passive")
		)
	)
	(footprint "antmicro-footprints:TP_Pad0.75mm_Drill0.2mm"
		(layer "F.Cu")
		(at 153.912 55.726 180)
		(property "Reference" "TP5"
			(at -0.438 -0.274 180)
			(layer "F.SilkS")
			(effects
				(font
					(size 0.7 0.7)
					(thickness 0.15)
				)
				(justify left bottom)
			)
		)
		(property "Value" "TP_Pad0.75mm_Drill0.2mm"
			(at 0 1.2 180)
			(layer "F.Fab")
			(effects
				(font
					(size 0.7 0.7)
					(thickness 0.15)
				)
				(justify left bottom)
			)
		)
		(property "Description" "SMT test point"
			(at 0 0 180)
			(layer "F.Fab")
			(hide yes)
			(effects
				(font
					(size 1.27 1.27)
					(thickness 0.15)
				)
			)
		)
		(property "MPN" ""
			(at 0 0 180)
			(unlocked yes)
			(layer "F.Fab")
			(hide yes)
			(effects
				(font
					(size 1 1)
					(thickness 0.15)
				)
			)
		)
		(property "Manufacturer" ""
			(at 0 0 180)
			(unlocked yes)
			(layer "F.Fab")
			(hide yes)
			(effects
				(font
					(size 1 1)
					(thickness 0.15)
				)
			)
		)
		(property "Author" "Antmicro"
			(at 0 0 180)
			(unlocked yes)
			(layer "F.Fab")
			(hide yes)
			(effects
				(font
					(size 1 1)
					(thickness 0.15)
				)
			)
		)
		(property "License" "Apache-2.0"
			(at 0 0 180)
			(unlocked yes)
			(layer "F.Fab")
			(hide yes)
			(effects
				(font
					(size 1 1)
					(thickness 0.15)
				)
			)
		)
		(sheetname "/USB-PD/")
		(sheetfile "usb-pd.kicad_sch")
		(attr exclude_from_pos_files exclude_from_bom)
		(fp_circle
			(center 0 0)
			(end 0.475 0)
			(stroke
				(width 0.05)
				(type default)
			)
			(fill no)
			(layer "F.CrtYd")
		)
		(fp_text user "Author: Antmicro"
			(at -0.4 3.901 180)
			(layer "F.Fab")
			(effects
				(font
					(size 0.7 0.7)
					(thickness 0.15)
				)
				(justify left bottom)
			)
		)
		(fp_text user "${REFERENCE}"
			(at -0.4 2.7 180)
			(layer "F.Fab")
			(effects
				(font
					(size 0.7 0.7)
					(thickness 0.15)
				)
				(justify left bottom)
			)
		)
		(fp_text user "License: Apache-2.0"
			(at -0.4 5.101 180)
			(layer "F.Fab")
			(effects
				(font
					(size 0.7 0.7)
					(thickness 0.15)
				)
				(justify left bottom)
			)
		)
		(pad "1" thru_hole circle
			(at 0 0 180)
			(size 0.75 0.75)
			(drill 0.2)
			(layers "*.Cu" "*.Mask")
			(remove_unused_layers no)
			(net 144 "/USB-PD/~{HPI_INT}")
			(pinfunction "1")
			(pintype "passive")
		)
	)
)
